FILE_TYPE = CONNECTIVITY;
{Allegro Design Entry HDL 17.2-2016 S081 (4005846) 1/11/2022}
"PAGE_NUMBER" = 235;
0"NC";
1"P3V3_AUX\g";
2"P3V3_AUX\g";
3"P3V3_AUX\g";
4"GND\g";
5"GND\g"CDS_PHYS_NET_NAME"GND";
6"GND\g";
7"GND\g";
8"JTAG_BMC_SW_TDO";
9"JTAG_BMC_SW_TDI";
10"JTAG_BMC_SW_TCK";
11"JTAG_BMC_SW_TMS";
12"JTAG_BMC_SW_TCK_R";
13"JTAG_BMC_SW_TMS_R";
14"JTAG_BMC_SW_TDI_R";
15"JTAG_BMC_SW_TDO_R";
16"JTAG_BMC_SW_R_OE";
17"JTAG_BMC_TDO_R";
18"JTAG_BMC_TDI_R";
19"JTAG_BMC_TMS_R";
20"JTAG_BMC_TCK_R";
21"JTAG_BMC_SW_OE"CDS_PHYS_NET_NAME"JTAG_BMC_SW_OE";
22"PU_JTAG_SW_PU"CDS_PHYS_NET_NAME"PU_JTAG_SW_PU";
23"JTAG_BMC_TDI";
24"JTAG_BMC_TDO";
25"JTAG_BMC_TCK";
26"JTAG_BMC_TMS";
%"UNIVERSAL_GND"
"1","(-2225,5200)","0","logical_power","I1";
;
CDS_LIB"logical_power"
HDL_POWER"GND";
"A"4;
%"UNIVERSAL_GND"
"1","(-750,4275)","0","logical_power","I10";
;
CDS_LIB"logical_power"
HDL_POWER"GND";
"A"5;
%"Q_RES"
"2","(-750,4850)","0","pure_quanta","I11";
;
PART_NUMBER"CS21002FB06"
VALUE"1K"
PACK_TYPE"0402LF"
MATERIAL"CHIP"
WATTAGE"1/16W"
TOLERANCE"1%"
$LOCATION"R4623"
CDS_LIB"pure_quanta"
CDS_LOCATION"R4623"
$SEC"1"
CDS_SEC"1";
"A"
$PN"1"2;
"B"
$PN"2"22;
%"UNIVERSAL_POWER"
"1","(-750,5050)","0","logical_power","I12";
;
HDL_POWER"P3V3_AUX"
CDS_LIB"logical_power";
"A"2;
%"CONN3_210HP1030BR1"
"1","(200,4550)","0","pure_quanta","I13";
;
PART_NUMBER"DFHD03MS213"
PART_TYPE"THLF"
MATERIAL"IO"
VALUE"CONN3_210-HP1-030BR1"
$LOCATION"JP16"
CDS_LIB"pure_quanta"
CDS_LMAN_SYM_OUTLINE"-50,100,50,-100"
NEEDS_NO_SIZE"TRUE"
CDS_LOCATION"JP16"
$SEC"1"
CDS_SEC"1";
"1"
$PN"1"22;
"2"
$PN"2"21;
"3"
$PN"3"5;
%"Q_RES"
"1","(-500,5775)","0","pure_quanta","I14";
;
PART_NUMBER"CS00002JB13"
WATTAGE"1/16W"
VALUE"0"
TOLERANCE"5%"
PACK_TYPE"0402LF"
MATERIAL"CHIP"
$LOCATION"R4624"
CDS_LIB"pure_quanta"
CDS_LOCATION"R4624"
$SEC"1"
CDS_SEC"1";
"B"
$PN"2"16;
"A"
$PN"1"21;
%"Q_RES"
"1","(-250,6225)","0","pure_quanta","I15";
;
PART_NUMBER"CS00002JB13"
MATERIAL"CHIP"
VALUE"0"
$LOCATION"R4629"
CDS_LIB"pure_quanta"
PACK_TYPE"0402LF"
TOLERANCE"5%"
WATTAGE"1/16W"
CDS_LOCATION"R4629"
$SEC"1"
CDS_SEC"1";
"B"
$PN"2"20;
"A"
$PN"1"25;
%"Q_RES"
"1","(-250,6375)","0","pure_quanta","I16";
;
PART_NUMBER"CS00002JB13"
VALUE"0"
MATERIAL"CHIP"
$LOCATION"R4628"
CDS_LIB"pure_quanta"
PACK_TYPE"0402LF"
TOLERANCE"5%"
WATTAGE"1/16W"
CDS_LOCATION"R4628"
$SEC"1"
CDS_SEC"1";
"B"
$PN"2"19;
"A"
$PN"1"26;
%"Q_RES"
"1","(-250,6525)","0","pure_quanta","I17";
;
PART_NUMBER"CS00002JB13"
MATERIAL"CHIP"
VALUE"0"
$LOCATION"R4627"
CDS_LIB"pure_quanta"
WATTAGE"1/16W"
TOLERANCE"5%"
PACK_TYPE"0402LF"
CDS_LOCATION"R4627"
$SEC"1"
CDS_SEC"1";
"B"
$PN"2"18;
"A"
$PN"1"23;
%"Q_RES"
"1","(-250,6675)","0","pure_quanta","I18";
;
PART_NUMBER"CS00002JB13"
MATERIAL"CHIP"
VALUE"0"
$LOCATION"R4626"
WATTAGE"1/16W"
TOLERANCE"5%"
PACK_TYPE"0402LF"
CDS_LIB"pure_quanta"
CDS_LOCATION"R4626"
$SEC"1"
CDS_SEC"1";
"B"
$PN"2"17;
"A"
$PN"1"24;
%"74CBTLV3126PW"
"1","(1575,6475)","0","pure_quanta","I19";
;
PART_NUMBER"AL003126K08"
MATERIAL"IC"
VALUE"74CBTLV3126PW"
PART_TYPE"SMLF"
$LOCATION"U327"
CDS_LMAN_SYM_OUTLINE"-250,350,250,-350"
NEEDS_NO_SIZE"TRUE"
CDS_LIB"pure_quanta"
CDS_LOCATION"U327"
$SEC"1"
CDS_SEC"1";
"VCC"
$PN"14"3;
"4OE"
$PN"13"16;
"4A"
$PN"12"17;
"4B"
$PN"11"15;
"3OE"
$PN"10"16;
"3A"
$PN"9"18;
"GND"
$PN"7"6;
"1A"
$PN"2"20;
"2B"
$PN"6"13;
"1B"
$PN"3"12;
"2OE"
$PN"4"16;
"1OE"
$PN"1"16;
"3B"
$PN"8"14;
"2A"
$PN"5"19;
%"UNIVERSAL_GND"
"1","(2100,6000)","0","logical_power","I20";
;
HDL_POWER"GND"
CDS_LIB"logical_power";
"A"6;
%"UNIVERSAL_POWER"
"1","(2075,7350)","0","logical_power","I21";
;
HDL_POWER"P3V3_AUX"
CDS_LIB"logical_power";
"A"3;
%"UNIVERSAL_GND"
"1","(2225,6875)","0","logical_power","I22";
;
CDS_LIB"logical_power"
HDL_POWER"GND";
"A"7;
%"Q_CAP"
"1","(2225,7075)","0","pure_quanta","I23";
;
PART_NUMBER"CH4104K1B00"
VALUE"0.1UF"
VOLTAGE"25V"
MATERIAL"X7R"
TOLERANCE"10%"
PACK_TYPE"0402"
$LOCATION"C2348"
CDS_LIB"pure_quanta"
CDS_LOCATION"C2348"
$SEC"1"
CDS_SEC"1";
"B"
$PN"2"7;
"A"
$PN"1"3;
%"Q_RES"
"1","(3400,6225)","0","pure_quanta","I24";
;
PART_NUMBER"CS00002JB13"
MATERIAL"CHIP"
VALUE"0"
$LOCATION"R4633"
CDS_LIB"pure_quanta"
WATTAGE"1/16W"
TOLERANCE"5%"
PACK_TYPE"0402LF"
CDS_LOCATION"R4633"
$SEC"1"
CDS_SEC"1";
"B"
$PN"2"10;
"A"
$PN"1"12;
%"Q_RES"
"1","(3400,6525)","0","pure_quanta","I25";
;
PART_NUMBER"CS00002JB13"
VALUE"0"
MATERIAL"CHIP"
$LOCATION"R4631"
CDS_LIB"pure_quanta"
PACK_TYPE"0402LF"
TOLERANCE"5%"
WATTAGE"1/16W"
CDS_LOCATION"R4631"
$SEC"1"
CDS_SEC"1";
"B"
$PN"2"9;
"A"
$PN"1"14;
%"Q_RES"
"1","(3400,6375)","0","pure_quanta","I26";
;
PART_NUMBER"CS00002JB13"
MATERIAL"CHIP"
VALUE"0"
$LOCATION"R4632"
CDS_LIB"pure_quanta"
WATTAGE"1/16W"
TOLERANCE"5%"
PACK_TYPE"0402LF"
CDS_LOCATION"R4632"
$SEC"1"
CDS_SEC"1";
"B"
$PN"2"11;
"A"
$PN"1"13;
%"Q_RES"
"1","(3400,6675)","0","pure_quanta","I27";
;
PART_NUMBER"CS00002JB13"
VALUE"0"
MATERIAL"CHIP"
$LOCATION"R4630"
CDS_LIB"pure_quanta"
PACK_TYPE"0402LF"
TOLERANCE"5%"
WATTAGE"1/16W"
CDS_LOCATION"R4630"
$SEC"1"
CDS_SEC"1";
"B"
$PN"2"8;
"A"
$PN"1"15;
%"Q_RES"
"2","(-2225,5475)","0","pure_quanta","I3";
;
PART_NUMBER"CS31002FB08"
MATERIAL"CHIP"
PACK_TYPE"0402LF"
VALUE"10K"
TOLERANCE"1%"
WATTAGE"1/16W"
$LOCATION"R4635"
CDS_LIB"pure_quanta"
CDS_LOCATION"R4635"
$SEC"1"
CDS_SEC"1";
"A"
$PN"1"21;
"B"
$PN"2"4;
%"Q_RES"
"2","(-2250,6000)","0","pure_quanta","I4";
;
PART_NUMBER"CS21002FB06"
TOLERANCE"1%"
PACK_TYPE"0402LF"
VALUE"1K"
MATERIAL"EMPTY"
WATTAGE"1/16W"
$LOCATION"R4634"
CDS_LIB"pure_quanta"
CDS_LOCATION"R4634"
$SEC"1"
CDS_SEC"1";
"A"
$PN"1"1;
"B"
$PN"2"21;
%"UNIVERSAL_POWER"
"1","(-2250,6275)","0","logical_power","I5";
;
HDL_POWER"P3V3_AUX"
CDS_LIB"logical_power";
"A"1;
END.
